# SCM (Grand Teton) — schematic netlist excerpt (pin names and nets, part order shuffled) for the footprints in the layout excerpt that follows; sources: Cadence DE-HDL packaged netlist, KiCad conversion of 12092022_DA0F0TMDCD0_F0T_Management_Board_D_brd_V3_OCP.brd

C248  Q_CAP  10UF 6.3V 20% X6S  pkg C0402  page 46 : A = P3V3_AUX ; B = GND
C121  Q_CAP  22UF 6.3V 20% X6S  pkg C0603  page 16 : A = P1V8_AUX ; B = GND

(kicad_pcb
	(version 20260206)
	(generator "pcbnew")
	(generator_version "10.0")
	(general
		(thickness 1.6)
		(legacy_teardrops no)
	)
	(paper "A4")
	(title_block
		(title "12092022_DA0F0TMDCD0_F0T_Management_Board_D_brd_V3_OCP.brd")
		(comment 1 "Grand Teton / footprints 1086-1087 of 1440")
	)
	(layers
		(0 "F.Cu" signal "TOP")
		(4 "In1.Cu" signal "GND")
		(6 "In2.Cu" signal "IN1")
		(8 "In3.Cu" signal "GND1")
		(10 "In4.Cu" signal "IN2")
		(12 "In5.Cu" signal "VCC")
		(14 "In6.Cu" signal "VCC1")
		(16 "In7.Cu" signal "IN3")
		(18 "In8.Cu" signal "GND2")
		(20 "In9.Cu" signal "IN4")
		(22 "In10.Cu" signal "GND3")
		(2 "B.Cu" signal "BOTTOM")
		(9 "F.Adhes" user "F.Adhesive")
		(11 "B.Adhes" user "B.Adhesive")
		(13 "F.Paste" user "Package Geometry/Pastemask Top")
		(15 "B.Paste" user "Package Geometry/Pastemask Bottom")
		(5 "F.SilkS" user "Ref Des/Silkscreen Top")
		(7 "B.SilkS" user "Ref Des/Silkscreen Bottom")
		(1 "F.Mask" user "Board Geometry/Soldermask Top")
		(3 "B.Mask" user "Board Geometry/Soldermask Bottom")
		(17 "Dwgs.User" user "User.Drawings")
		(19 "Cmts.User" user "User.Comments")
		(21 "Eco1.User" user "User.Eco1")
		(23 "Eco2.User" user "User.Eco2")
		(25 "Edge.Cuts" user "Board Geometry/Outline")
		(27 "Margin" user)
		(31 "F.CrtYd" user "Package Geometry/Place Bound Top")
		(29 "B.CrtYd" user "Package Geometry/Place Bound Bottom")
		(35 "F.Fab" user "Ref Des/Assembly Top")
		(33 "B.Fab" user "Ref Des/Assembly Bottom")
	)
	(footprint ""
		(layer "B.Cu")
		(at 84.452968 -99.238054 180)
		(property "Reference" "C248"
			(at 0 0 0)
			(layer "B.SilkS")
			(hide yes)
			(effects
				(font
					(size 1.27 1.27)
				)
				(justify mirror)
			)
		)
		(property "Value" ""
			(at 0 0 0)
			(layer "B.Fab")
			(effects
				(font
					(size 1.27 1.27)
				)
				(justify mirror)
			)
		)
		(duplicate_pad_numbers_are_jumpers no)
		(fp_line
			(start 0.7874 0.4064)
			(end 0.7874 -0.4064)
			(stroke
				(width 0.1524)
				(type default)
			)
			(layer "B.SilkS")
		)
		(fp_line
			(start 0.7874 -0.4064)
			(end -0.7874 -0.4064)
			(stroke
				(width 0.1524)
				(type default)
			)
			(layer "B.SilkS")
		)
		(fp_line
			(start -0.7874 0.4064)
			(end 0.7874 0.4064)
			(stroke
				(width 0.1524)
				(type default)
			)
			(layer "B.SilkS")
		)
		(fp_line
			(start -0.7874 -0.4064)
			(end -0.7874 0.4064)
			(stroke
				(width 0.1524)
				(type default)
			)
			(layer "B.SilkS")
		)
		(fp_line
			(start 0.67945 0.3048)
			(end 0.67945 -0.305054)
			(stroke
				(width 0.1)
				(type default)
			)
			(layer "B.Fab")
		)
		(fp_line
			(start 0.67945 -0.305054)
			(end 0.12065 -0.305054)
			(stroke
				(width 0.1)
				(type default)
			)
			(layer "B.Fab")
		)
		(fp_line
			(start 0.12065 0.3048)
			(end 0.67945 0.3048)
			(stroke
				(width 0.1)
				(type default)
			)
			(layer "B.Fab")
		)
		(fp_line
			(start 0.12065 0.2794)
			(end 0.12065 0.3048)
			(stroke
				(width 0.1)
				(type default)
			)
			(layer "B.Fab")
		)
		(fp_line
			(start 0.12065 -0.2794)
			(end -0.12065 -0.2794)
			(stroke
				(width 0.1)
				(type default)
			)
			(layer "B.Fab")
		)
		(fp_line
			(start 0.12065 -0.305054)
			(end 0.12065 -0.2794)
			(stroke
				(width 0.1)
				(type default)
			)
			(layer "B.Fab")
		)
		(fp_line
			(start -0.120396 0.3048)
			(end -0.120396 0.2794)
			(stroke
				(width 0.1)
				(type default)
			)
			(layer "B.Fab")
		)
		(fp_line
			(start -0.120396 0.2794)
			(end 0.12065 0.2794)
			(stroke
				(width 0.1)
				(type default)
			)
			(layer "B.Fab")
		)
		(fp_line
			(start -0.12065 -0.2794)
			(end -0.12065 -0.3048)
			(stroke
				(width 0.1)
				(type default)
			)
			(layer "B.Fab")
		)
		(fp_line
			(start -0.12065 -0.3048)
			(end -0.67945 -0.3048)
			(stroke
				(width 0.1)
				(type default)
			)
			(layer "B.Fab")
		)
		(fp_line
			(start -0.67945 0.3048)
			(end -0.120396 0.3048)
			(stroke
				(width 0.1)
				(type default)
			)
			(layer "B.Fab")
		)
		(fp_line
			(start -0.67945 -0.3048)
			(end -0.67945 0.3048)
			(stroke
				(width 0.1)
				(type default)
			)
			(layer "B.Fab")
		)
		(pad "1" smd circle
			(at 0.40005 0)
			(size 0 0)
			(layers "B.Cu" "B.Mask" "B.Paste")
			(net "P3V3_AUX")
		)
		(pad "2" smd circle
			(at -0.40005 0)
			(size 0 0)
			(layers "B.Cu" "B.Mask" "B.Paste")
			(net "GND")
		)
	)
	(footprint ""
		(layer "B.Cu")
		(at 54.880764 -52.938934 90)
		(property "Reference" "C121"
			(at 0 0 90)
			(layer "B.SilkS")
			(hide yes)
			(effects
				(font
					(size 1.27 1.27)
				)
				(justify mirror)
			)
		)
		(property "Value" ""
			(at 0 0 90)
			(layer "B.Fab")
			(effects
				(font
					(size 1.27 1.27)
				)
				(justify mirror)
			)
		)
		(duplicate_pad_numbers_are_jumpers no)
		(fp_line
			(start 1.2954 -0.5842)
			(end -1.2954 -0.5842)
			(stroke
				(width 0.1524)
				(type default)
			)
			(layer "B.SilkS")
		)
		(fp_line
			(start 0 -0.5842)
			(end 0 0.5842)
			(stroke
				(width 0.1524)
				(type default)
			)
			(layer "B.SilkS")
		)
		(fp_line
			(start -1.2954 -0.5842)
			(end -1.2954 0.5842)
			(stroke
				(width 0.1524)
				(type default)
			)
			(layer "B.SilkS")
		)
		(fp_line
			(start 1.2954 0.5842)
			(end 1.2954 -0.5842)
			(stroke
				(width 0.1524)
				(type default)
			)
			(layer "B.SilkS")
		)
		(fp_line
			(start -1.2954 0.5842)
			(end 1.2954 0.5842)
			(stroke
				(width 0.1524)
				(type default)
			)
			(layer "B.SilkS")
		)
		(fp_line
			(start 0.8636 -0.4572)
			(end -0.8636 -0.4572)
			(stroke
				(width 0.1)
				(type default)
			)
			(layer "B.Fab")
		)
		(fp_line
			(start -0.8636 -0.4572)
			(end -0.8636 -0.4064)
			(stroke
				(width 0.1)
				(type default)
			)
			(layer "B.Fab")
		)
		(fp_line
			(start 1.1938 -0.4064)
			(end 0.8636 -0.4064)
			(stroke
				(width 0.1)
				(type default)
			)
			(layer "B.Fab")
		)
		(fp_line
			(start 0.8636 -0.4064)
			(end 0.8636 -0.4572)
			(stroke
				(width 0.1)
				(type default)
			)
			(layer "B.Fab")
		)
		(fp_line
			(start -0.8636 -0.4064)
			(end -1.1938 -0.4064)
			(stroke
				(width 0.1)
				(type default)
			)
			(layer "B.Fab")
		)
		(fp_line
			(start -1.1938 -0.4064)
			(end -1.1938 0.4064)
			(stroke
				(width 0.1)
				(type default)
			)
			(layer "B.Fab")
		)
		(fp_line
			(start 1.1938 0.4064)
			(end 1.1938 -0.4064)
			(stroke
				(width 0.1)
				(type default)
			)
			(layer "B.Fab")
		)
		(fp_line
			(start 0.8636 0.4064)
			(end 1.1938 0.4064)
			(stroke
				(width 0.1)
				(type default)
			)
			(layer "B.Fab")
		)
		(fp_line
			(start -0.8636 0.4064)
			(end -0.8636 0.4572)
			(stroke
				(width 0.1)
				(type default)
			)
			(layer "B.Fab")
		)
		(fp_line
			(start -1.1938 0.4064)
			(end -0.8636 0.4064)
			(stroke
				(width 0.1)
				(type default)
			)
			(layer "B.Fab")
		)
		(fp_line
			(start 0.8636 0.4572)
			(end 0.8636 0.4064)
			(stroke
				(width 0.1)
				(type default)
			)
			(layer "B.Fab")
		)
		(fp_line
			(start -0.8636 0.4572)
			(end 0.8636 0.4572)
			(stroke
				(width 0.1)
				(type default)
			)
			(layer "B.Fab")
		)
		(pad "1" smd rect
			(at 0.7366 0)
			(size 0.7112 0.8128)
			(layers "B.Cu" "B.Mask" "B.Paste")
			(net "P1V8_AUX")
		)
		(pad "2" smd rect
			(at -0.7366 0)
			(size 0.7112 0.8128)
			(layers "B.Cu" "B.Mask" "B.Paste")
			(net "GND")
		)
	)
)
